(kicad_pcb
	(version 20260206)
	(generator "pcbnew")
	(generator_version "10.0")
	(general
		(thickness 1.6)
		(legacy_teardrops no)
	)
	(paper "A4")
	(title_block
		(title "04192023_DAF0TMB3IC0_F0TG_MB_C_brd_V02_OCP.brd")
		(comment 1 "Grand Teton / footprints 5806-5812 of 8354")
	)
	(layers
		(0 "F.Cu" signal "TOP")
		(4 "In1.Cu" signal "GND")
		(6 "In2.Cu" signal "IN1")
		(8 "In3.Cu" signal "GND1")
		(10 "In4.Cu" signal "IN2")
		(12 "In5.Cu" signal "GND2")
		(14 "In6.Cu" signal "IN3")
		(16 "In7.Cu" signal "GND3")
		(18 "In8.Cu" signal "VCC")
		(20 "In9.Cu" signal "VCC1")
		(22 "In10.Cu" signal "GND4")
		(24 "In11.Cu" signal "IN4")
		(26 "In12.Cu" signal "GND5")
		(28 "In13.Cu" signal "IN5")
		(30 "In14.Cu" signal "GND6")
		(32 "In15.Cu" signal "IN6")
		(34 "In16.Cu" signal "GND7")
		(2 "B.Cu" signal "BOTTOM")
		(9 "F.Adhes" user "F.Adhesive")
		(11 "B.Adhes" user "B.Adhesive")
		(13 "F.Paste" user "Package Geometry/Pastemask Top")
		(15 "B.Paste" user "Package Geometry/Pastemask Bottom")
		(5 "F.SilkS" user "Ref Des/Silkscreen Top")
		(7 "B.SilkS" user "Ref Des/Silkscreen Bottom")
		(1 "F.Mask" user "Board Geometry/Soldermask Top")
		(3 "B.Mask" user "Board Geometry/Soldermask Bottom")
		(17 "Dwgs.User" user "User.Drawings")
		(19 "Cmts.User" user "User.Comments")
		(21 "Eco1.User" user "User.Eco1")
		(23 "Eco2.User" user "User.Eco2")
		(25 "Edge.Cuts" user "Board Geometry/Outline")
		(27 "Margin" user)
		(31 "F.CrtYd" user "Package Geometry/Place Bound Top")
		(29 "B.CrtYd" user "Package Geometry/Place Bound Bottom")
		(35 "F.Fab" user "Ref Des/Assembly Top")
		(33 "B.Fab" user "Ref Des/Assembly Bottom")
	)
	(footprint ""
		(layer "B.Cu")
		(at 113.919 -417.576)
		(property "Reference" "Q108"
			(at 0.311658 -2.625598 0)
			(unlocked yes)
			(layer "B.SilkS")
			(effects
				(font
					(size 0.7874 0.5842)
					(thickness 0.1524)
				)
				(justify left mirror)
			)
		)
		(property "Value" ""
			(at 0 0 0)
			(layer "B.Fab")
			(effects
				(font
					(size 1.27 1.27)
				)
				(justify mirror)
			)
		)
		(duplicate_pad_numbers_are_jumpers no)
		(fp_line
			(start -1.332738 -1.100074)
			(end -1.332738 1.100074)
			(stroke
				(width 0.1524)
				(type default)
			)
			(layer "B.SilkS")
		)
		(fp_line
			(start -1.332738 1.100074)
			(end 1.332738 1.100074)
			(stroke
				(width 0.1524)
				(type default)
			)
			(layer "B.SilkS")
		)
		(fp_line
			(start -0.4826 -1.100074)
			(end -1.332738 -1.100074)
			(stroke
				(width 0.1524)
				(type default)
			)
			(layer "B.SilkS")
		)
		(fp_line
			(start 0 -0.541274)
			(end -0.4826 -1.100074)
			(stroke
				(width 0.1524)
				(type default)
			)
			(layer "B.SilkS")
		)
		(fp_line
			(start 0.4826 -1.100074)
			(end 0 -0.541274)
			(stroke
				(width 0.1524)
				(type default)
			)
			(layer "B.SilkS")
		)
		(fp_line
			(start 1.332738 -1.100074)
			(end 0.4826 -1.100074)
			(stroke
				(width 0.1524)
				(type default)
			)
			(layer "B.SilkS")
		)
		(fp_line
			(start 1.332738 1.100074)
			(end 1.332738 -1.100074)
			(stroke
				(width 0.1524)
				(type default)
			)
			(layer "B.SilkS")
		)
		(fp_poly
			(pts
				(xy 0.914146 -1.289558) (xy 1.257554 -1.99517) (xy 0.555752 -1.987804)
			)
			(stroke
				(width 0)
				(type default)
			)
			(fill yes)
			(layer "B.SilkS")
		)
		(fp_line
			(start -0.674878 -1.100074)
			(end -0.674878 1.100074)
			(stroke
				(width 0.1)
				(type default)
			)
			(layer "B.Fab")
		)
		(fp_line
			(start -0.674878 1.100074)
			(end 0.674878 1.100074)
			(stroke
				(width 0.1)
				(type default)
			)
			(layer "B.Fab")
		)
		(fp_line
			(start 0.674878 -1.100074)
			(end -0.674878 -1.100074)
			(stroke
				(width 0.1)
				(type default)
			)
			(layer "B.Fab")
		)
		(fp_line
			(start 0.674878 1.100074)
			(end 0.674878 -1.100074)
			(stroke
				(width 0.1)
				(type default)
			)
			(layer "B.Fab")
		)
		(fp_poly
			(pts
				(xy 2.2352 -0.298958) (xy 2.2352 -1.001014) (xy 1.533144 -0.649986)
			)
			(stroke
				(width 0)
				(type default)
			)
			(fill yes)
			(layer "B.Fab")
		)
		(pad "1" smd rect
			(at 0.94996 -0.649986 90)
			(size 0.4318 0.508)
			(layers "B.Cu" "B.Mask" "B.Paste")
			(net "GND")
		)
		(pad "2" smd rect
			(at 0.94996 0 90)
			(size 0.4318 0.508)
			(layers "B.Cu" "B.Mask" "B.Paste")
			(net "GPU_FPGA_EROT_FATALERR_N")
		)
		(pad "3" smd rect
			(at 0.94996 0.649986 90)
			(size 0.4318 0.508)
			(layers "B.Cu" "B.Mask" "B.Paste")
			(net "GPU_FPGA_EROT_FATALERR_ISO_N")
		)
		(pad "4" smd rect
			(at -0.94996 0.649986 90)
			(size 0.4318 0.508)
			(layers "B.Cu" "B.Mask" "B.Paste")
			(net "GND")
		)
		(pad "5" smd rect
			(at -0.94996 0 90)
			(size 0.4318 0.508)
			(layers "B.Cu" "B.Mask" "B.Paste")
			(net "GPU_FPGA_EROT_FATALERR")
		)
		(pad "6" smd rect
			(at -0.94996 -0.649986 90)
			(size 0.4318 0.508)
			(layers "B.Cu" "B.Mask" "B.Paste")
			(net "GPU_FPGA_EROT_FATALERR")
		)
	)
	(footprint ""
		(layer "B.Cu")
		(at 231.648 -337.439 90)
		(property "Reference" "R6766"
			(at 0 0 90)
			(layer "B.SilkS")
			(hide yes)
			(effects
				(font
					(size 1.27 1.27)
				)
				(justify mirror)
			)
		)
		(property "Value" ""
			(at 0 0 90)
			(layer "B.Fab")
			(effects
				(font
					(size 1.27 1.27)
				)
				(justify mirror)
			)
		)
		(duplicate_pad_numbers_are_jumpers no)
		(fp_line
			(start 0.32512 -0.175006)
			(end -0.32512 -0.175006)
			(stroke
				(width 0.1)
				(type default)
			)
			(layer "B.Fab")
		)
		(fp_line
			(start -0.32512 -0.175006)
			(end -0.32512 0.175006)
			(stroke
				(width 0.1)
				(type default)
			)
			(layer "B.Fab")
		)
		(fp_line
			(start 0.32512 0.175006)
			(end 0.32512 -0.175006)
			(stroke
				(width 0.1)
				(type default)
			)
			(layer "B.Fab")
		)
		(fp_line
			(start -0.32512 0.175006)
			(end 0.32512 0.175006)
			(stroke
				(width 0.1)
				(type default)
			)
			(layer "B.Fab")
		)
		(pad "1" smd rect
			(at 0.2667 0 270)
			(size 0.3048 0.381)
			(layers "B.Cu" "B.Mask" "B.Paste")
			(net "P1V8_CPU0_RT_1D")
		)
		(pad "2" smd rect
			(at -0.2667 0 90)
			(size 0.3048 0.381)
			(layers "B.Cu" "B.Mask" "B.Paste")
			(net "SMB_RT_CPU0_P3_R_SDA")
		)
	)
	(footprint ""
		(layer "B.Cu")
		(at 65.530984 -408.517344 90)
		(property "Reference" "C6671"
			(at 0 0 90)
			(layer "B.SilkS")
			(hide yes)
			(effects
				(font
					(size 1.27 1.27)
				)
				(justify mirror)
			)
		)
		(property "Value" ""
			(at 0 0 90)
			(layer "B.Fab")
			(effects
				(font
					(size 1.27 1.27)
				)
				(justify mirror)
			)
		)
		(duplicate_pad_numbers_are_jumpers no)
		(fp_line
			(start 0.299974 -0.150114)
			(end -0.299974 -0.150114)
			(stroke
				(width 0.1)
				(type default)
			)
			(layer "B.Fab")
		)
		(fp_line
			(start -0.299974 -0.150114)
			(end -0.299974 0.150114)
			(stroke
				(width 0.1)
				(type default)
			)
			(layer "B.Fab")
		)
		(fp_line
			(start 0.299974 0.150114)
			(end 0.299974 -0.150114)
			(stroke
				(width 0.1)
				(type default)
			)
			(layer "B.Fab")
		)
		(fp_line
			(start -0.299974 0.150114)
			(end 0.299974 0.150114)
			(stroke
				(width 0.1)
				(type default)
			)
			(layer "B.Fab")
		)
		(pad "1" smd rect
			(at 0.2667 0 270)
			(size 0.3048 0.381)
			(layers "B.Cu" "B.Mask" "B.Paste")
			(net "P5E_CPU1_P1_TX_BUF_C_DP<5>")
		)
		(pad "2" smd rect
			(at -0.2667 0 270)
			(size 0.3048 0.381)
			(layers "B.Cu" "B.Mask" "B.Paste")
			(net "P5E_CPU1_P1_TX_BUF_DP<5>")
		)
	)
	(footprint ""
		(layer "B.Cu")
		(at 247.651778 -315.95568 -90)
		(property "Reference" "PC6509"
			(at 0 0 90)
			(layer "B.SilkS")
			(hide yes)
			(effects
				(font
					(size 1.27 1.27)
				)
				(justify mirror)
			)
		)
		(property "Value" ""
			(at 0 0 90)
			(layer "B.Fab")
			(effects
				(font
					(size 1.27 1.27)
				)
				(justify mirror)
			)
		)
		(duplicate_pad_numbers_are_jumpers no)
		(fp_line
			(start -1.524 0.762)
			(end 1.524 0.762)
			(stroke
				(width 0.1524)
				(type default)
			)
			(layer "B.SilkS")
		)
		(fp_line
			(start 1.524 0.762)
			(end 1.524 -0.762)
			(stroke
				(width 0.1524)
				(type default)
			)
			(layer "B.SilkS")
		)
		(fp_line
			(start -1.524 -0.762)
			(end -1.524 0.762)
			(stroke
				(width 0.1524)
				(type default)
			)
			(layer "B.SilkS")
		)
		(fp_line
			(start 1.524 -0.762)
			(end -1.524 -0.762)
			(stroke
				(width 0.1524)
				(type default)
			)
			(layer "B.SilkS")
		)
		(fp_line
			(start -1.1049 0.724916)
			(end -1.1049 -0.724916)
			(stroke
				(width 0.1)
				(type default)
			)
			(layer "B.Fab")
		)
		(fp_line
			(start 1.1049 0.724916)
			(end -1.1049 0.724916)
			(stroke
				(width 0.1)
				(type default)
			)
			(layer "B.Fab")
		)
		(fp_line
			(start -1.1049 -0.724916)
			(end 1.1049 -0.724916)
			(stroke
				(width 0.1)
				(type default)
			)
			(layer "B.Fab")
		)
		(fp_line
			(start 1.1049 -0.724916)
			(end 1.1049 0.724916)
			(stroke
				(width 0.1)
				(type default)
			)
			(layer "B.Fab")
		)
		(pad "1" smd rect
			(at 0.889 0 270)
			(size 1.016 1.27)
			(layers "B.Cu" "B.Mask" "B.Paste")
			(net "P1V8_CPU0_RT_1D")
		)
		(pad "2" smd rect
			(at -0.889 0 270)
			(size 1.016 1.27)
			(layers "B.Cu" "B.Mask" "B.Paste")
			(net "GND")
		)
	)
	(footprint ""
		(layer "B.Cu")
		(at 102.783386 -269.307564)
		(property "Reference" "C2393"
			(at 0 0 0)
			(layer "B.SilkS")
			(hide yes)
			(effects
				(font
					(size 1.27 1.27)
				)
				(justify mirror)
			)
		)
		(property "Value" ""
			(at 0 0 0)
			(layer "B.Fab")
			(effects
				(font
					(size 1.27 1.27)
				)
				(justify mirror)
			)
		)
		(duplicate_pad_numbers_are_jumpers no)
		(fp_line
			(start -0.7874 -0.4064)
			(end -0.7874 0.4064)
			(stroke
				(width 0.1524)
				(type default)
			)
			(layer "B.SilkS")
		)
		(fp_line
			(start -0.7874 0.4064)
			(end 0.7874 0.4064)
			(stroke
				(width 0.1524)
				(type default)
			)
			(layer "B.SilkS")
		)
		(fp_line
			(start 0.7874 -0.4064)
			(end -0.7874 -0.4064)
			(stroke
				(width 0.1524)
				(type default)
			)
			(layer "B.SilkS")
		)
		(fp_line
			(start 0.7874 0.4064)
			(end 0.7874 -0.4064)
			(stroke
				(width 0.1524)
				(type default)
			)
			(layer "B.SilkS")
		)
		(fp_line
			(start -0.67945 -0.3048)
			(end -0.67945 0.3048)
			(stroke
				(width 0.1)
				(type default)
			)
			(layer "B.Fab")
		)
		(fp_line
			(start -0.67945 0.3048)
			(end -0.120396 0.3048)
			(stroke
				(width 0.1)
				(type default)
			)
			(layer "B.Fab")
		)
		(fp_line
			(start -0.12065 -0.3048)
			(end -0.67945 -0.3048)
			(stroke
				(width 0.1)
				(type default)
			)
			(layer "B.Fab")
		)
		(fp_line
			(start -0.12065 -0.2794)
			(end -0.12065 -0.3048)
			(stroke
				(width 0.1)
				(type default)
			)
			(layer "B.Fab")
		)
		(fp_line
			(start -0.120396 0.2794)
			(end 0.12065 0.2794)
			(stroke
				(width 0.1)
				(type default)
			)
			(layer "B.Fab")
		)
		(fp_line
			(start -0.120396 0.3048)
			(end -0.120396 0.2794)
			(stroke
				(width 0.1)
				(type default)
			)
			(layer "B.Fab")
		)
		(fp_line
			(start 0.12065 -0.305054)
			(end 0.12065 -0.2794)
			(stroke
				(width 0.1)
				(type default)
			)
			(layer "B.Fab")
		)
		(fp_line
			(start 0.12065 -0.2794)
			(end -0.12065 -0.2794)
			(stroke
				(width 0.1)
				(type default)
			)
			(layer "B.Fab")
		)
		(fp_line
			(start 0.12065 0.2794)
			(end 0.12065 0.3048)
			(stroke
				(width 0.1)
				(type default)
			)
			(layer "B.Fab")
		)
		(fp_line
			(start 0.12065 0.3048)
			(end 0.67945 0.3048)
			(stroke
				(width 0.1)
				(type default)
			)
			(layer "B.Fab")
		)
		(fp_line
			(start 0.67945 -0.305054)
			(end 0.12065 -0.305054)
			(stroke
				(width 0.1)
				(type default)
			)
			(layer "B.Fab")
		)
		(fp_line
			(start 0.67945 0.3048)
			(end 0.67945 -0.305054)
			(stroke
				(width 0.1)
				(type default)
			)
			(layer "B.Fab")
		)
		(pad "1" smd circle
			(at 0.40005 0 180)
			(size 0 0)
			(layers "B.Cu" "B.Mask" "B.Paste")
			(net "PVDDCR_CPU1_P1")
		)
		(pad "2" smd circle
			(at -0.40005 0 180)
			(size 0 0)
			(layers "B.Cu" "B.Mask" "B.Paste")
			(net "GND")
		)
	)
	(footprint ""
		(layer "B.Cu")
		(at 113.587276 -391.340848 -90)
		(property "Reference" "C469"
			(at 0 0 90)
			(layer "B.SilkS")
			(hide yes)
			(effects
				(font
					(size 1.27 1.27)
				)
				(justify mirror)
			)
		)
		(property "Value" ""
			(at 0 0 90)
			(layer "B.Fab")
			(effects
				(font
					(size 1.27 1.27)
				)
				(justify mirror)
			)
		)
		(duplicate_pad_numbers_are_jumpers no)
		(fp_line
			(start -0.7874 0.4064)
			(end 0.7874 0.4064)
			(stroke
				(width 0.1524)
				(type default)
			)
			(layer "B.SilkS")
		)
		(fp_line
			(start 0.7874 0.4064)
			(end 0.7874 -0.4064)
			(stroke
				(width 0.1524)
				(type default)
			)
			(layer "B.SilkS")
		)
		(fp_line
			(start -0.7874 -0.4064)
			(end -0.7874 0.4064)
			(stroke
				(width 0.1524)
				(type default)
			)
			(layer "B.SilkS")
		)
		(fp_line
			(start 0.7874 -0.4064)
			(end -0.7874 -0.4064)
			(stroke
				(width 0.1524)
				(type default)
			)
			(layer "B.SilkS")
		)
		(fp_line
			(start -0.67945 0.3048)
			(end -0.120396 0.3048)
			(stroke
				(width 0.1)
				(type default)
			)
			(layer "B.Fab")
		)
		(fp_line
			(start -0.120396 0.3048)
			(end -0.120396 0.2794)
			(stroke
				(width 0.1)
				(type default)
			)
			(layer "B.Fab")
		)
		(fp_line
			(start 0.12065 0.3048)
			(end 0.67945 0.3048)
			(stroke
				(width 0.1)
				(type default)
			)
			(layer "B.Fab")
		)
		(fp_line
			(start 0.67945 0.3048)
			(end 0.67945 -0.305054)
			(stroke
				(width 0.1)
				(type default)
			)
			(layer "B.Fab")
		)
		(fp_line
			(start -0.120396 0.2794)
			(end 0.12065 0.2794)
			(stroke
				(width 0.1)
				(type default)
			)
			(layer "B.Fab")
		)
		(fp_line
			(start 0.12065 0.2794)
			(end 0.12065 0.3048)
			(stroke
				(width 0.1)
				(type default)
			)
			(layer "B.Fab")
		)
		(fp_line
			(start -0.12065 -0.2794)
			(end -0.12065 -0.3048)
			(stroke
				(width 0.1)
				(type default)
			)
			(layer "B.Fab")
		)
		(fp_line
			(start 0.12065 -0.2794)
			(end -0.12065 -0.2794)
			(stroke
				(width 0.1)
				(type default)
			)
			(layer "B.Fab")
		)
		(fp_line
			(start -0.67945 -0.3048)
			(end -0.67945 0.3048)
			(stroke
				(width 0.1)
				(type default)
			)
			(layer "B.Fab")
		)
		(fp_line
			(start -0.12065 -0.3048)
			(end -0.67945 -0.3048)
			(stroke
				(width 0.1)
				(type default)
			)
			(layer "B.Fab")
		)
		(fp_line
			(start 0.12065 -0.305054)
			(end 0.12065 -0.2794)
			(stroke
				(width 0.1)
				(type default)
			)
			(layer "B.Fab")
		)
		(fp_line
			(start 0.67945 -0.305054)
			(end 0.12065 -0.305054)
			(stroke
				(width 0.1)
				(type default)
			)
			(layer "B.Fab")
		)
		(pad "1" smd circle
			(at 0.40005 0 90)
			(size 0 0)
			(layers "B.Cu" "B.Mask" "B.Paste")
			(net "P0V9_CPU1_RT3_2A")
		)
		(pad "2" smd circle
			(at -0.40005 0 90)
			(size 0 0)
			(layers "B.Cu" "B.Mask" "B.Paste")
			(net "GND")
		)
	)
	(footprint ""
		(layer "B.Cu")
		(at 235.086398 -213.258654)
		(property "Reference" "R257"
			(at 0 0 0)
			(layer "B.SilkS")
			(hide yes)
			(effects
				(font
					(size 1.27 1.27)
				)
				(justify mirror)
			)
		)
		(property "Value" ""
			(at 0 0 0)
			(layer "B.Fab")
			(effects
				(font
					(size 1.27 1.27)
				)
				(justify mirror)
			)
		)
		(duplicate_pad_numbers_are_jumpers no)
		(fp_line
			(start -0.7874 -0.4064)
			(end -0.7874 0.4064)
			(stroke
				(width 0.1524)
				(type default)
			)
			(layer "B.SilkS")
		)
		(fp_line
			(start -0.7874 0.4064)
			(end 0.7874 0.4064)
			(stroke
				(width 0.1524)
				(type default)
			)
			(layer "B.SilkS")
		)
		(fp_line
			(start 0.7874 -0.4064)
			(end -0.7874 -0.4064)
			(stroke
				(width 0.1524)
				(type default)
			)
			(layer "B.SilkS")
		)
		(fp_line
			(start 0.7874 0.4064)
			(end 0.7874 -0.4064)
			(stroke
				(width 0.1524)
				(type default)
			)
			(layer "B.SilkS")
		)
		(fp_line
			(start -0.67945 -0.3048)
			(end -0.67945 0.3048)
			(stroke
				(width 0.1)
				(type default)
			)
			(layer "B.Fab")
		)
		(fp_line
			(start -0.67945 0.3048)
			(end -0.120396 0.3048)
			(stroke
				(width 0.1)
				(type default)
			)
			(layer "B.Fab")
		)
		(fp_line
			(start -0.12065 -0.3048)
			(end -0.67945 -0.3048)
			(stroke
				(width 0.1)
				(type default)
			)
			(layer "B.Fab")
		)
		(fp_line
			(start -0.12065 -0.2794)
			(end -0.12065 -0.3048)
			(stroke
				(width 0.1)
				(type default)
			)
			(layer "B.Fab")
		)
		(fp_line
			(start -0.120396 0.2794)
			(end 0.12065 0.2794)
			(stroke
				(width 0.1)
				(type default)
			)
			(layer "B.Fab")
		)
		(fp_line
			(start -0.120396 0.3048)
			(end -0.120396 0.2794)
			(stroke
				(width 0.1)
				(type default)
			)
			(layer "B.Fab")
		)
		(fp_line
			(start 0.12065 -0.305054)
			(end 0.12065 -0.2794)
			(stroke
				(width 0.1)
				(type default)
			)
			(layer "B.Fab")
		)
		(fp_line
			(start 0.12065 -0.2794)
			(end -0.12065 -0.2794)
			(stroke
				(width 0.1)
				(type default)
			)
			(layer "B.Fab")
		)
		(fp_line
			(start 0.12065 0.2794)
			(end 0.12065 0.3048)
			(stroke
				(width 0.1)
				(type default)
			)
			(layer "B.Fab")
		)
		(fp_line
			(start 0.12065 0.3048)
			(end 0.67945 0.3048)
			(stroke
				(width 0.1)
				(type default)
			)
			(layer "B.Fab")
		)
		(fp_line
			(start 0.67945 -0.305054)
			(end 0.12065 -0.305054)
			(stroke
				(width 0.1)
				(type default)
			)
			(layer "B.Fab")
		)
		(fp_line
			(start 0.67945 0.3048)
			(end 0.67945 -0.305054)
			(stroke
				(width 0.1)
				(type default)
			)
			(layer "B.Fab")
		)
		(pad "1" smd rect
			(at 0.40005 0)
			(size 0.4572 0.508)
			(layers "B.Cu" "B.Mask" "B.Paste")
			(net "SMB_CPU0_CPU1_APML_BUF1_SDA_R2")
		)
		(pad "2" smd rect
			(at -0.40005 0)
			(size 0.4572 0.508)
			(layers "B.Cu" "B.Mask" "B.Paste")
			(net "SMB_CPU0_CPU1_APML_SDA_R2")
		)
	)
)
